# T6G (Grand Teton) — schematic netlist excerpt (pin names and nets, part order shuffled) for the footprints in the layout excerpt that follows; sources: Cadence DE-HDL packaged netlist, KiCad conversion of 04192023_DAF0TMB3IC0_F0TG_MB_C_brd_V02_OCP.brd

C194  Q_CAP  0.1UF 16V 10% X7R  pkg C0402  page 171 : A = P3V3_AUX ; B = GND
C830  Q_CAP_DIFFBUS  DIFF BUS_0.22UF 6.3V 20% X6S  pkg C0201  page 65 : \1\ = P5E_CPU1_P0_TX_C_DN<3> ; \2\ = P5E_CPU1_P0_TX_DN<3>
PR3965  Q_RES  15K 1% CHIP  pkg 0402LF  page 146 : A = P3V3_E1S_OV_0 ; B = GND

(kicad_pcb
	(version 20260206)
	(generator "pcbnew")
	(generator_version "10.0")
	(general
		(thickness 1.6)
		(legacy_teardrops no)
	)
	(paper "A4")
	(title_block
		(title "04192023_DAF0TMB3IC0_F0TG_MB_C_brd_V02_OCP.brd")
		(comment 1 "Grand Teton / footprints 4386-4388 of 8354")
	)
	(layers
		(0 "F.Cu" signal "TOP")
		(4 "In1.Cu" signal "GND")
		(6 "In2.Cu" signal "IN1")
		(8 "In3.Cu" signal "GND1")
		(10 "In4.Cu" signal "IN2")
		(12 "In5.Cu" signal "GND2")
		(14 "In6.Cu" signal "IN3")
		(16 "In7.Cu" signal "GND3")
		(18 "In8.Cu" signal "VCC")
		(20 "In9.Cu" signal "VCC1")
		(22 "In10.Cu" signal "GND4")
		(24 "In11.Cu" signal "IN4")
		(26 "In12.Cu" signal "GND5")
		(28 "In13.Cu" signal "IN5")
		(30 "In14.Cu" signal "GND6")
		(32 "In15.Cu" signal "IN6")
		(34 "In16.Cu" signal "GND7")
		(2 "B.Cu" signal "BOTTOM")
		(9 "F.Adhes" user "F.Adhesive")
		(11 "B.Adhes" user "B.Adhesive")
		(13 "F.Paste" user "Package Geometry/Pastemask Top")
		(15 "B.Paste" user "Package Geometry/Pastemask Bottom")
		(5 "F.SilkS" user "Ref Des/Silkscreen Top")
		(7 "B.SilkS" user "Ref Des/Silkscreen Bottom")
		(1 "F.Mask" user "Board Geometry/Soldermask Top")
		(3 "B.Mask" user "Board Geometry/Soldermask Bottom")
		(17 "Dwgs.User" user "User.Drawings")
		(19 "Cmts.User" user "User.Comments")
		(21 "Eco1.User" user "User.Eco1")
		(23 "Eco2.User" user "User.Eco2")
		(25 "Edge.Cuts" user "Board Geometry/Outline")
		(27 "Margin" user)
		(31 "F.CrtYd" user "Package Geometry/Place Bound Top")
		(29 "B.CrtYd" user "Package Geometry/Place Bound Bottom")
		(35 "F.Fab" user "Ref Des/Assembly Top")
		(33 "B.Fab" user "Ref Des/Assembly Bottom")
	)
	(footprint ""
		(layer "F.Cu")
		(at 217.881962 -67.324478 180)
		(property "Reference" "PR3965"
			(at 0 0 180)
			(layer "F.SilkS")
			(hide yes)
			(effects
				(font
					(size 1.27 1.27)
				)
			)
		)
		(property "Value" ""
			(at 0 0 180)
			(layer "F.Fab")
			(effects
				(font
					(size 1.27 1.27)
				)
			)
		)
		(duplicate_pad_numbers_are_jumpers no)
		(fp_line
			(start 0.7874 0.4064)
			(end -0.7874 0.4064)
			(stroke
				(width 0.1524)
				(type default)
			)
			(layer "F.SilkS")
		)
		(fp_line
			(start 0.7874 -0.4064)
			(end 0.7874 0.4064)
			(stroke
				(width 0.1524)
				(type default)
			)
			(layer "F.SilkS")
		)
		(fp_line
			(start -0.7874 0.4064)
			(end -0.7874 -0.4064)
			(stroke
				(width 0.1524)
				(type default)
			)
			(layer "F.SilkS")
		)
		(fp_line
			(start -0.7874 -0.4064)
			(end 0.7874 -0.4064)
			(stroke
				(width 0.1524)
				(type default)
			)
			(layer "F.SilkS")
		)
		(fp_line
			(start 0.67945 0.3048)
			(end 0.120396 0.3048)
			(stroke
				(width 0.1)
				(type default)
			)
			(layer "F.Fab")
		)
		(fp_line
			(start 0.67945 -0.3048)
			(end 0.67945 0.3048)
			(stroke
				(width 0.1)
				(type default)
			)
			(layer "F.Fab")
		)
		(fp_line
			(start 0.12065 -0.2794)
			(end 0.12065 -0.3048)
			(stroke
				(width 0.1)
				(type default)
			)
			(layer "F.Fab")
		)
		(fp_line
			(start 0.12065 -0.3048)
			(end 0.67945 -0.3048)
			(stroke
				(width 0.1)
				(type default)
			)
			(layer "F.Fab")
		)
		(fp_line
			(start 0.120396 0.3048)
			(end 0.120396 0.2794)
			(stroke
				(width 0.1)
				(type default)
			)
			(layer "F.Fab")
		)
		(fp_line
			(start 0.120396 0.2794)
			(end -0.12065 0.2794)
			(stroke
				(width 0.1)
				(type default)
			)
			(layer "F.Fab")
		)
		(fp_line
			(start -0.12065 0.3048)
			(end -0.67945 0.3048)
			(stroke
				(width 0.1)
				(type default)
			)
			(layer "F.Fab")
		)
		(fp_line
			(start -0.12065 0.2794)
			(end -0.12065 0.3048)
			(stroke
				(width 0.1)
				(type default)
			)
			(layer "F.Fab")
		)
		(fp_line
			(start -0.12065 -0.2794)
			(end 0.12065 -0.2794)
			(stroke
				(width 0.1)
				(type default)
			)
			(layer "F.Fab")
		)
		(fp_line
			(start -0.12065 -0.305054)
			(end -0.12065 -0.2794)
			(stroke
				(width 0.1)
				(type default)
			)
			(layer "F.Fab")
		)
		(fp_line
			(start -0.67945 0.3048)
			(end -0.67945 -0.305054)
			(stroke
				(width 0.1)
				(type default)
			)
			(layer "F.Fab")
		)
		(fp_line
			(start -0.67945 -0.305054)
			(end -0.12065 -0.305054)
			(stroke
				(width 0.1)
				(type default)
			)
			(layer "F.Fab")
		)
		(pad "1" smd circle
			(at -0.40005 0 180)
			(size 0 0)
			(layers "F.Cu" "F.Mask" "F.Paste")
			(net "P3V3_E1S_OV_0")
		)
		(pad "2" smd circle
			(at 0.40005 0 180)
			(size 0 0)
			(layers "F.Cu" "F.Mask" "F.Paste")
			(net "GND")
		)
	)
	(footprint ""
		(layer "F.Cu")
		(at 136.188958 -62.28207 90)
		(property "Reference" "C194"
			(at 0 0 90)
			(layer "F.SilkS")
			(hide yes)
			(effects
				(font
					(size 1.27 1.27)
				)
			)
		)
		(property "Value" ""
			(at 0 0 90)
			(layer "F.Fab")
			(effects
				(font
					(size 1.27 1.27)
				)
			)
		)
		(duplicate_pad_numbers_are_jumpers no)
		(fp_line
			(start 0.7874 -0.4064)
			(end 0.7874 0.4064)
			(stroke
				(width 0.1524)
				(type default)
			)
			(layer "F.SilkS")
		)
		(fp_line
			(start -0.7874 -0.4064)
			(end 0.7874 -0.4064)
			(stroke
				(width 0.1524)
				(type default)
			)
			(layer "F.SilkS")
		)
		(fp_line
			(start 0.7874 0.4064)
			(end -0.7874 0.4064)
			(stroke
				(width 0.1524)
				(type default)
			)
			(layer "F.SilkS")
		)
		(fp_line
			(start -0.7874 0.4064)
			(end -0.7874 -0.4064)
			(stroke
				(width 0.1524)
				(type default)
			)
			(layer "F.SilkS")
		)
		(fp_line
			(start -0.12065 -0.305054)
			(end -0.12065 -0.2794)
			(stroke
				(width 0.1)
				(type default)
			)
			(layer "F.Fab")
		)
		(fp_line
			(start -0.67945 -0.305054)
			(end -0.12065 -0.305054)
			(stroke
				(width 0.1)
				(type default)
			)
			(layer "F.Fab")
		)
		(fp_line
			(start 0.67945 -0.3048)
			(end 0.67945 0.3048)
			(stroke
				(width 0.1)
				(type default)
			)
			(layer "F.Fab")
		)
		(fp_line
			(start 0.12065 -0.3048)
			(end 0.67945 -0.3048)
			(stroke
				(width 0.1)
				(type default)
			)
			(layer "F.Fab")
		)
		(fp_line
			(start 0.12065 -0.2794)
			(end 0.12065 -0.3048)
			(stroke
				(width 0.1)
				(type default)
			)
			(layer "F.Fab")
		)
		(fp_line
			(start -0.12065 -0.2794)
			(end 0.12065 -0.2794)
			(stroke
				(width 0.1)
				(type default)
			)
			(layer "F.Fab")
		)
		(fp_line
			(start 0.120396 0.2794)
			(end -0.12065 0.2794)
			(stroke
				(width 0.1)
				(type default)
			)
			(layer "F.Fab")
		)
		(fp_line
			(start -0.12065 0.2794)
			(end -0.12065 0.3048)
			(stroke
				(width 0.1)
				(type default)
			)
			(layer "F.Fab")
		)
		(fp_line
			(start 0.67945 0.3048)
			(end 0.120396 0.3048)
			(stroke
				(width 0.1)
				(type default)
			)
			(layer "F.Fab")
		)
		(fp_line
			(start 0.120396 0.3048)
			(end 0.120396 0.2794)
			(stroke
				(width 0.1)
				(type default)
			)
			(layer "F.Fab")
		)
		(fp_line
			(start -0.12065 0.3048)
			(end -0.67945 0.3048)
			(stroke
				(width 0.1)
				(type default)
			)
			(layer "F.Fab")
		)
		(fp_line
			(start -0.67945 0.3048)
			(end -0.67945 -0.305054)
			(stroke
				(width 0.1)
				(type default)
			)
			(layer "F.Fab")
		)
		(pad "1" smd circle
			(at -0.40005 0 90)
			(size 0 0)
			(layers "F.Cu" "F.Mask" "F.Paste")
			(net "P3V3_AUX")
		)
		(pad "2" smd circle
			(at 0.40005 0 90)
			(size 0 0)
			(layers "F.Cu" "F.Mask" "F.Paste")
			(net "GND")
		)
	)
	(footprint ""
		(layer "F.Cu")
		(at 45.605954 -370.57203 -90)
		(property "Reference" "C830"
			(at 0 0 270)
			(layer "F.SilkS")
			(hide yes)
			(effects
				(font
					(size 1.27 1.27)
				)
			)
		)
		(property "Value" ""
			(at 0 0 270)
			(layer "F.Fab")
			(effects
				(font
					(size 1.27 1.27)
				)
			)
		)
		(duplicate_pad_numbers_are_jumpers no)
		(fp_line
			(start -0.299974 0.150114)
			(end -0.299974 -0.150114)
			(stroke
				(width 0.1)
				(type default)
			)
			(layer "F.Fab")
		)
		(fp_line
			(start 0.299974 0.150114)
			(end -0.299974 0.150114)
			(stroke
				(width 0.1)
				(type default)
			)
			(layer "F.Fab")
		)
		(fp_line
			(start -0.299974 -0.150114)
			(end 0.299974 -0.150114)
			(stroke
				(width 0.1)
				(type default)
			)
			(layer "F.Fab")
		)
		(fp_line
			(start 0.299974 -0.150114)
			(end 0.299974 0.150114)
			(stroke
				(width 0.1)
				(type default)
			)
			(layer "F.Fab")
		)
		(pad "1" smd rect
			(at -0.2667 0 270)
			(size 0.3048 0.381)
			(layers "F.Cu" "F.Mask" "F.Paste")
			(net "P5E_CPU1_P0_TX_C_DN<3>")
		)
		(pad "2" smd rect
			(at 0.2667 0 270)
			(size 0.3048 0.381)
			(layers "F.Cu" "F.Mask" "F.Paste")
			(net "P5E_CPU1_P0_TX_DN<3>")
		)
	)
)
